(kicad_pcb
	(version 20260206)
	(generator "pcbnew")
	(generator_version "10.0")
	(general
		(thickness 1.6)
		(legacy_teardrops no)
	)
	(paper "A4")
	(title_block
		(title "01162023_DA0F0TEBIF0_F0T_Expander_BD_F_brd_V02_OCP.brd")
		(comment 1 "Grand Teton / footprints 742-748 of 9728")
	)
	(layers
		(0 "F.Cu" signal "TOP")
		(4 "In1.Cu" signal "GND")
		(6 "In2.Cu" signal "VCC")
		(8 "In3.Cu" signal "VCC1")
		(10 "In4.Cu" signal "GND1")
		(12 "In5.Cu" signal "IN1")
		(14 "In6.Cu" signal "GND2")
		(16 "In7.Cu" signal "IN2")
		(18 "In8.Cu" signal "GND3")
		(20 "In9.Cu" signal "IN3")
		(22 "In10.Cu" signal "GND4")
		(24 "In11.Cu" signal "IN4")
		(26 "In12.Cu" signal "GND5")
		(28 "In13.Cu" signal "IN5")
		(30 "In14.Cu" signal "GND6")
		(32 "In15.Cu" signal "IN6")
		(34 "In16.Cu" signal "GND7")
		(2 "B.Cu" signal "BOTTOM")
		(9 "F.Adhes" user "F.Adhesive")
		(11 "B.Adhes" user "B.Adhesive")
		(13 "F.Paste" user "Package Geometry/Pastemask Top")
		(15 "B.Paste" user "Package Geometry/Pastemask Bottom")
		(5 "F.SilkS" user "Ref Des/Silkscreen Top")
		(7 "B.SilkS" user "Ref Des/Silkscreen Bottom")
		(1 "F.Mask" user "Board Geometry/Soldermask Top")
		(3 "B.Mask" user "Board Geometry/Soldermask Bottom")
		(17 "Dwgs.User" user "User.Drawings")
		(19 "Cmts.User" user "User.Comments")
		(21 "Eco1.User" user "User.Eco1")
		(23 "Eco2.User" user "User.Eco2")
		(25 "Edge.Cuts" user "Board Geometry/Outline")
		(27 "Margin" user)
		(31 "F.CrtYd" user "Package Geometry/Place Bound Top")
		(29 "B.CrtYd" user "Package Geometry/Place Bound Bottom")
		(35 "F.Fab" user "Ref Des/Assembly Top")
		(33 "B.Fab" user "Ref Des/Assembly Bottom")
	)
	(footprint ""
		(layer "F.Cu")
		(at 239.813338 -140.392404 180)
		(property "Reference" "PC315"
			(at 0 0 180)
			(layer "F.SilkS")
			(hide yes)
			(effects
				(font
					(size 1.27 1.27)
				)
			)
		)
		(property "Value" ""
			(at 0 0 180)
			(layer "F.Fab")
			(effects
				(font
					(size 1.27 1.27)
				)
			)
		)
		(duplicate_pad_numbers_are_jumpers no)
		(fp_line
			(start 0.7874 0.4064)
			(end -0.7874 0.4064)
			(stroke
				(width 0.1524)
				(type default)
			)
			(layer "F.SilkS")
		)
		(fp_line
			(start 0.7874 -0.4064)
			(end 0.7874 0.4064)
			(stroke
				(width 0.1524)
				(type default)
			)
			(layer "F.SilkS")
		)
		(fp_line
			(start -0.7874 0.4064)
			(end -0.7874 -0.4064)
			(stroke
				(width 0.1524)
				(type default)
			)
			(layer "F.SilkS")
		)
		(fp_line
			(start -0.7874 -0.4064)
			(end 0.7874 -0.4064)
			(stroke
				(width 0.1524)
				(type default)
			)
			(layer "F.SilkS")
		)
		(fp_line
			(start 0.6858 0.3048)
			(end 0.1016 0.3048)
			(stroke
				(width 0.1)
				(type default)
			)
			(layer "F.Fab")
		)
		(fp_line
			(start 0.6858 -0.3048)
			(end 0.6858 0.3048)
			(stroke
				(width 0.1)
				(type default)
			)
			(layer "F.Fab")
		)
		(fp_line
			(start 0.1016 0.3048)
			(end 0.1016 0.2794)
			(stroke
				(width 0.1)
				(type default)
			)
			(layer "F.Fab")
		)
		(fp_line
			(start 0.1016 0.2794)
			(end -0.1016 0.2794)
			(stroke
				(width 0.1)
				(type default)
			)
			(layer "F.Fab")
		)
		(fp_line
			(start 0.1016 -0.2794)
			(end 0.1016 -0.3048)
			(stroke
				(width 0.1)
				(type default)
			)
			(layer "F.Fab")
		)
		(fp_line
			(start 0.1016 -0.3048)
			(end 0.6858 -0.3048)
			(stroke
				(width 0.1)
				(type default)
			)
			(layer "F.Fab")
		)
		(fp_line
			(start -0.1016 0.3048)
			(end -0.6858 0.3048)
			(stroke
				(width 0.1)
				(type default)
			)
			(layer "F.Fab")
		)
		(fp_line
			(start -0.1016 0.2794)
			(end -0.1016 0.3048)
			(stroke
				(width 0.1)
				(type default)
			)
			(layer "F.Fab")
		)
		(fp_line
			(start -0.1016 -0.2794)
			(end 0.1016 -0.2794)
			(stroke
				(width 0.1)
				(type default)
			)
			(layer "F.Fab")
		)
		(fp_line
			(start -0.1016 -0.3048)
			(end -0.1016 -0.2794)
			(stroke
				(width 0.1)
				(type default)
			)
			(layer "F.Fab")
		)
		(fp_line
			(start -0.6858 0.3048)
			(end -0.6858 -0.3048)
			(stroke
				(width 0.1)
				(type default)
			)
			(layer "F.Fab")
		)
		(fp_line
			(start -0.6858 -0.3048)
			(end -0.1016 -0.3048)
			(stroke
				(width 0.1)
				(type default)
			)
			(layer "F.Fab")
		)
		(pad "1" smd rect
			(at -0.40005 0)
			(size 0.4572 0.508)
			(layers "F.Cu" "F.Mask" "F.Paste")
			(net "P12V_NIC4_SS")
		)
		(pad "2" smd rect
			(at 0.40005 0)
			(size 0.4572 0.508)
			(layers "F.Cu" "F.Mask" "F.Paste")
			(net "GND")
		)
	)
	(footprint ""
		(layer "F.Cu")
		(at 426.543724 -43.85691)
		(property "Reference" "R663"
			(at 0 0 0)
			(layer "F.SilkS")
			(hide yes)
			(effects
				(font
					(size 1.27 1.27)
				)
			)
		)
		(property "Value" ""
			(at 0 0 0)
			(layer "F.Fab")
			(effects
				(font
					(size 1.27 1.27)
				)
			)
		)
		(duplicate_pad_numbers_are_jumpers no)
		(fp_line
			(start -0.7874 -0.4064)
			(end 0.7874 -0.4064)
			(stroke
				(width 0.1524)
				(type default)
			)
			(layer "F.SilkS")
		)
		(fp_line
			(start -0.7874 0.4064)
			(end -0.7874 -0.4064)
			(stroke
				(width 0.1524)
				(type default)
			)
			(layer "F.SilkS")
		)
		(fp_line
			(start 0.7874 -0.4064)
			(end 0.7874 0.4064)
			(stroke
				(width 0.1524)
				(type default)
			)
			(layer "F.SilkS")
		)
		(fp_line
			(start 0.7874 0.4064)
			(end -0.7874 0.4064)
			(stroke
				(width 0.1524)
				(type default)
			)
			(layer "F.SilkS")
		)
		(fp_line
			(start -0.67945 -0.305054)
			(end -0.12065 -0.305054)
			(stroke
				(width 0.1)
				(type default)
			)
			(layer "F.Fab")
		)
		(fp_line
			(start -0.67945 0.3048)
			(end -0.67945 -0.305054)
			(stroke
				(width 0.1)
				(type default)
			)
			(layer "F.Fab")
		)
		(fp_line
			(start -0.12065 -0.305054)
			(end -0.12065 -0.2794)
			(stroke
				(width 0.1)
				(type default)
			)
			(layer "F.Fab")
		)
		(fp_line
			(start -0.12065 -0.2794)
			(end 0.12065 -0.2794)
			(stroke
				(width 0.1)
				(type default)
			)
			(layer "F.Fab")
		)
		(fp_line
			(start -0.12065 0.2794)
			(end -0.12065 0.3048)
			(stroke
				(width 0.1)
				(type default)
			)
			(layer "F.Fab")
		)
		(fp_line
			(start -0.12065 0.3048)
			(end -0.67945 0.3048)
			(stroke
				(width 0.1)
				(type default)
			)
			(layer "F.Fab")
		)
		(fp_line
			(start 0.120396 0.2794)
			(end -0.12065 0.2794)
			(stroke
				(width 0.1)
				(type default)
			)
			(layer "F.Fab")
		)
		(fp_line
			(start 0.120396 0.3048)
			(end 0.120396 0.2794)
			(stroke
				(width 0.1)
				(type default)
			)
			(layer "F.Fab")
		)
		(fp_line
			(start 0.12065 -0.3048)
			(end 0.67945 -0.3048)
			(stroke
				(width 0.1)
				(type default)
			)
			(layer "F.Fab")
		)
		(fp_line
			(start 0.12065 -0.2794)
			(end 0.12065 -0.3048)
			(stroke
				(width 0.1)
				(type default)
			)
			(layer "F.Fab")
		)
		(fp_line
			(start 0.67945 -0.3048)
			(end 0.67945 0.3048)
			(stroke
				(width 0.1)
				(type default)
			)
			(layer "F.Fab")
		)
		(fp_line
			(start 0.67945 0.3048)
			(end 0.120396 0.3048)
			(stroke
				(width 0.1)
				(type default)
			)
			(layer "F.Fab")
		)
		(pad "1" smd circle
			(at -0.40005 0)
			(size 0 0)
			(layers "F.Cu" "F.Mask" "F.Paste")
			(net "SSD14_ADC_A1")
		)
		(pad "2" smd circle
			(at 0.40005 0)
			(size 0 0)
			(layers "F.Cu" "F.Mask" "F.Paste")
			(net "GND")
		)
	)
	(footprint ""
		(layer "F.Cu")
		(at 363.833156 -114.933476)
		(property "Reference" "PU121"
			(at 3.502152 -2.790444 90)
			(unlocked yes)
			(layer "F.SilkS")
			(effects
				(font
					(size 0.7874 0.5842)
					(thickness 0.1524)
				)
			)
		)
		(property "Value" ""
			(at 0 0 0)
			(layer "F.Fab")
			(effects
				(font
					(size 1.27 1.27)
				)
			)
		)
		(duplicate_pad_numbers_are_jumpers no)
		(fp_line
			(start -1.239774 -1.495298)
			(end 1.239774 -1.495298)
			(stroke
				(width 0.1524)
				(type default)
			)
			(layer "F.SilkS")
		)
		(fp_line
			(start -1.239774 1.495298)
			(end -1.239774 -1.495298)
			(stroke
				(width 0.1524)
				(type default)
			)
			(layer "F.SilkS")
		)
		(fp_line
			(start 1.239774 -1.495298)
			(end 1.239774 1.495298)
			(stroke
				(width 0.1524)
				(type default)
			)
			(layer "F.SilkS")
		)
		(fp_line
			(start 1.239774 1.495298)
			(end -1.239774 1.495298)
			(stroke
				(width 0.1524)
				(type default)
			)
			(layer "F.SilkS")
		)
		(fp_poly
			(pts
				(xy -1.814576 -1.456944) (xy -2.533142 -0.738632) (xy -1.45542 -0.379476)
			)
			(stroke
				(width 0)
				(type default)
			)
			(fill yes)
			(layer "F.SilkS")
		)
		(fp_line
			(start -0.8001 -1.050036)
			(end 0.8001 -1.050036)
			(stroke
				(width 0.1)
				(type default)
			)
			(layer "F.Fab")
		)
		(fp_line
			(start -0.8001 1.050036)
			(end -0.8001 -1.050036)
			(stroke
				(width 0.1)
				(type default)
			)
			(layer "F.Fab")
		)
		(fp_line
			(start 0.8001 -1.050036)
			(end 0.8001 1.050036)
			(stroke
				(width 0.1)
				(type default)
			)
			(layer "F.Fab")
		)
		(fp_line
			(start 0.8001 1.050036)
			(end -0.8001 1.050036)
			(stroke
				(width 0.1)
				(type default)
			)
			(layer "F.Fab")
		)
		(fp_poly
			(pts
				(xy -2.458974 -0.508) (xy -2.458974 0.508) (xy -1.442974 0)
			)
			(stroke
				(width 0)
				(type default)
			)
			(fill yes)
			(layer "F.Fab")
		)
		(pad "1_2" smd circle
			(at -0.374904 0 90)
			(size 0 0)
			(layers "F.Cu" "F.Mask" "F.Paste")
			(net "P3V3_AUX")
		)
		(pad "3" smd rect
			(at -0.499872 0.999998)
			(size 0.254 0.7112)
			(layers "F.Cu" "F.Mask" "F.Paste")
			(net "GND")
		)
		(pad "4" smd rect
			(at 0 0.999998)
			(size 0.254 0.7112)
			(layers "F.Cu" "F.Mask" "F.Paste")
			(net "P3V3_NIC6_CO_ILIMIT")
		)
		(pad "5" smd rect
			(at 0.499872 0.999998)
			(size 0.254 0.7112)
			(layers "F.Cu" "F.Mask" "F.Paste")
			(net "P3V3_NIC6_CO_MODE")
		)
		(pad "6_7" smd circle
			(at 0.374904 0 270)
			(size 0 0)
			(layers "F.Cu" "F.Mask" "F.Paste")
			(net "P3V3_NIC6")
		)
		(pad "8" smd rect
			(at 0.499872 -0.999998)
			(size 0.254 0.7112)
			(layers "F.Cu" "F.Mask" "F.Paste")
			(net "P3V3_NIC6_CO_GATE")
		)
		(pad "9" smd rect
			(at 0 -0.999998)
			(size 0.254 0.7112)
			(layers "F.Cu" "F.Mask" "F.Paste")
			(net "P3V3_NIC6_CO_EN")
		)
		(pad "10" smd rect
			(at -0.499872 -0.999998)
			(size 0.254 0.7112)
			(layers "F.Cu" "F.Mask" "F.Paste")
			(net "P3V3_NIC6_CO_DV_DT")
		)
	)
	(footprint ""
		(layer "F.Cu")
		(at 443.802262 -435.658006 90)
		(property "Reference" "J46"
			(at -3.5052 -5.552948 90)
			(unlocked yes)
			(layer "F.SilkS")
			(effects
				(font
					(size 0.7874 0.5842)
					(thickness 0.1524)
				)
				(justify left)
			)
		)
		(property "Value" ""
			(at 0 0 90)
			(layer "F.Fab")
			(effects
				(font
					(size 1.27 1.27)
				)
			)
		)
		(duplicate_pad_numbers_are_jumpers no)
		(fp_line
			(start 3.330702 -4.771136)
			(end 0 4.011168)
			(stroke
				(width 0.1524)
				(type default)
			)
			(layer "F.SilkS")
		)
		(fp_line
			(start -3.330702 -4.771136)
			(end 3.330702 -4.771136)
			(stroke
				(width 0.1524)
				(type default)
			)
			(layer "F.SilkS")
		)
		(fp_line
			(start 0 4.011168)
			(end -3.330702 -4.771136)
			(stroke
				(width 0.1524)
				(type default)
			)
			(layer "F.SilkS")
		)
		(fp_line
			(start 3.330702 -4.771136)
			(end 0 4.011168)
			(stroke
				(width 0.1)
				(type default)
			)
			(layer "F.Fab")
		)
		(fp_line
			(start -3.330702 -4.771136)
			(end 3.330702 -4.771136)
			(stroke
				(width 0.1)
				(type default)
			)
			(layer "F.Fab")
		)
		(fp_line
			(start 0 4.011168)
			(end -3.330702 -4.771136)
			(stroke
				(width 0.1)
				(type default)
			)
			(layer "F.Fab")
		)
		(pad "1" thru_hole circle
			(at 0 0 90)
			(size 2.159 2.159)
			(drill 1.7018)
			(layers "*.Cu" "*.Mask")
			(remove_unused_layers no)
			(net "COUPON_GND1")
			(clearance 0.0254)
			(thermal_gap 0.0254)
		)
		(pad "2" thru_hole circle
			(at -1.27 -3.348736 90)
			(size 2.159 2.159)
			(drill 1.7018)
			(layers "*.Cu" "*.Mask")
			(remove_unused_layers no)
			(net "TDR_SE_50_OHM_TOP")
			(clearance 0.0254)
			(thermal_gap 0.0254)
		)
		(pad "3" thru_hole circle
			(at 1.27 -3.348736 90)
			(size 2.159 2.159)
			(drill 1.7018)
			(layers "*.Cu" "*.Mask")
			(remove_unused_layers no)
			(net "TDR_SE_50_OHM_TOP")
			(clearance 0.0254)
			(thermal_gap 0.0254)
		)
	)
	(footprint ""
		(layer "F.Cu")
		(at 359.156 -181.102 180)
		(property "Reference" "R4704"
			(at 0 0 180)
			(layer "F.SilkS")
			(hide yes)
			(effects
				(font
					(size 1.27 1.27)
				)
			)
		)
		(property "Value" ""
			(at 0 0 180)
			(layer "F.Fab")
			(effects
				(font
					(size 1.27 1.27)
				)
			)
		)
		(duplicate_pad_numbers_are_jumpers no)
		(fp_line
			(start 0.7874 0.4064)
			(end -0.7874 0.4064)
			(stroke
				(width 0.1524)
				(type default)
			)
			(layer "F.SilkS")
		)
		(fp_line
			(start 0.7874 -0.4064)
			(end 0.7874 0.4064)
			(stroke
				(width 0.1524)
				(type default)
			)
			(layer "F.SilkS")
		)
		(fp_line
			(start -0.7874 0.4064)
			(end -0.7874 -0.4064)
			(stroke
				(width 0.1524)
				(type default)
			)
			(layer "F.SilkS")
		)
		(fp_line
			(start -0.7874 -0.4064)
			(end 0.7874 -0.4064)
			(stroke
				(width 0.1524)
				(type default)
			)
			(layer "F.SilkS")
		)
		(fp_line
			(start 0.67945 0.3048)
			(end 0.120396 0.3048)
			(stroke
				(width 0.1)
				(type default)
			)
			(layer "F.Fab")
		)
		(fp_line
			(start 0.67945 -0.3048)
			(end 0.67945 0.3048)
			(stroke
				(width 0.1)
				(type default)
			)
			(layer "F.Fab")
		)
		(fp_line
			(start 0.12065 -0.2794)
			(end 0.12065 -0.3048)
			(stroke
				(width 0.1)
				(type default)
			)
			(layer "F.Fab")
		)
		(fp_line
			(start 0.12065 -0.3048)
			(end 0.67945 -0.3048)
			(stroke
				(width 0.1)
				(type default)
			)
			(layer "F.Fab")
		)
		(fp_line
			(start 0.120396 0.3048)
			(end 0.120396 0.2794)
			(stroke
				(width 0.1)
				(type default)
			)
			(layer "F.Fab")
		)
		(fp_line
			(start 0.120396 0.2794)
			(end -0.12065 0.2794)
			(stroke
				(width 0.1)
				(type default)
			)
			(layer "F.Fab")
		)
		(fp_line
			(start -0.12065 0.3048)
			(end -0.67945 0.3048)
			(stroke
				(width 0.1)
				(type default)
			)
			(layer "F.Fab")
		)
		(fp_line
			(start -0.12065 0.2794)
			(end -0.12065 0.3048)
			(stroke
				(width 0.1)
				(type default)
			)
			(layer "F.Fab")
		)
		(fp_line
			(start -0.12065 -0.2794)
			(end 0.12065 -0.2794)
			(stroke
				(width 0.1)
				(type default)
			)
			(layer "F.Fab")
		)
		(fp_line
			(start -0.12065 -0.305054)
			(end -0.12065 -0.2794)
			(stroke
				(width 0.1)
				(type default)
			)
			(layer "F.Fab")
		)
		(fp_line
			(start -0.67945 0.3048)
			(end -0.67945 -0.305054)
			(stroke
				(width 0.1)
				(type default)
			)
			(layer "F.Fab")
		)
		(fp_line
			(start -0.67945 -0.305054)
			(end -0.12065 -0.305054)
			(stroke
				(width 0.1)
				(type default)
			)
			(layer "F.Fab")
		)
		(pad "1" smd circle
			(at -0.40005 0 180)
			(size 0 0)
			(layers "F.Cu" "F.Mask" "F.Paste")
			(net "PCA9555_1_PEX1_A1")
		)
		(pad "2" smd circle
			(at 0.40005 0 180)
			(size 0 0)
			(layers "F.Cu" "F.Mask" "F.Paste")
			(net "P3V3_AUX")
		)
	)
	(footprint ""
		(layer "F.Cu")
		(at 245.813072 -369.875562 90)
		(property "Reference" "PQ6602"
			(at -8.218932 -2.080514 0)
			(unlocked yes)
			(layer "F.SilkS")
			(effects
				(font
					(size 0.7874 0.5842)
					(thickness 0.1524)
				)
				(justify left)
			)
		)
		(property "Value" ""
			(at 0 0 90)
			(layer "F.Fab")
			(effects
				(font
					(size 1.27 1.27)
				)
			)
		)
		(duplicate_pad_numbers_are_jumpers no)
		(fp_line
			(start 2.350008 -2.649982)
			(end 2.350008 -2.4892)
			(stroke
				(width 0.1524)
				(type default)
			)
			(layer "F.SilkS")
		)
		(fp_line
			(start -2.350008 -2.649982)
			(end 2.350008 -2.649982)
			(stroke
				(width 0.1524)
				(type default)
			)
			(layer "F.SilkS")
		)
		(fp_line
			(start -2.350008 -2.4384)
			(end -2.350008 -2.649982)
			(stroke
				(width 0.1524)
				(type default)
			)
			(layer "F.SilkS")
		)
		(fp_line
			(start 2.350008 2.4892)
			(end 2.350008 2.649982)
			(stroke
				(width 0.1524)
				(type default)
			)
			(layer "F.SilkS")
		)
		(fp_line
			(start 2.350008 2.649982)
			(end -2.350008 2.649982)
			(stroke
				(width 0.1524)
				(type default)
			)
			(layer "F.SilkS")
		)
		(fp_line
			(start -2.350008 2.649982)
			(end -2.350008 2.413)
			(stroke
				(width 0.1524)
				(type default)
			)
			(layer "F.SilkS")
		)
		(fp_poly
			(pts
				(xy -4.710684 -1.905) (xy -5.752084 -2.3241) (xy -5.752084 -1.524)
			)
			(stroke
				(width 0)
				(type default)
			)
			(fill yes)
			(layer "F.SilkS")
		)
		(fp_line
			(start 2.350008 -2.649982)
			(end 2.350008 2.649982)
			(stroke
				(width 0.1)
				(type default)
			)
			(layer "F.Fab")
		)
		(fp_line
			(start -2.350008 -2.649982)
			(end 2.350008 -2.649982)
			(stroke
				(width 0.1)
				(type default)
			)
			(layer "F.Fab")
		)
		(fp_line
			(start 2.350008 2.649982)
			(end -2.350008 2.649982)
			(stroke
				(width 0.1)
				(type default)
			)
			(layer "F.Fab")
		)
		(fp_line
			(start -2.350008 2.649982)
			(end -2.350008 -2.649982)
			(stroke
				(width 0.1)
				(type default)
			)
			(layer "F.Fab")
		)
		(fp_poly
			(pts
				(xy -3.717544 -1.905) (xy -4.758944 -2.3241) (xy -4.758944 -1.524)
			)
			(stroke
				(width 0)
				(type default)
			)
			(fill yes)
			(layer "F.Fab")
		)
		(pad "1" smd rect
			(at -2.999994 -1.905)
			(size 0.7112 1.1684)
			(layers "F.Cu" "F.Mask" "F.Paste")
			(net "P12V_AUX")
		)
		(pad "2" smd rect
			(at -2.999994 -0.635)
			(size 0.7112 1.1684)
			(layers "F.Cu" "F.Mask" "F.Paste")
			(net "P12V_AUX")
		)
		(pad "3" smd rect
			(at -2.999994 0.635)
			(size 0.7112 1.1684)
			(layers "F.Cu" "F.Mask" "F.Paste")
			(net "P12V_AUX")
		)
		(pad "4" smd rect
			(at -2.999994 1.905)
			(size 0.7112 1.1684)
			(layers "F.Cu" "F.Mask" "F.Paste")
			(net "HS_GATE2_R_1")
		)
		(pad "5" smd circle
			(at 0.925068 0)
			(size 0 0)
			(layers "F.Cu" "F.Mask" "F.Paste")
			(net "P12V_STBY_R2")
		)
		(zone
			(layer "F.Cu")
			(hatch none 0.5)
			(connect_pads
				(clearance 0)
			)
			(min_thickness 0.25)
			(keepout
				(tracks not_allowed)
				(vias allowed)
				(pads allowed)
				(copperpour not_allowed)
				(footprints allowed)
			)
			(placement
				(enabled no)
				(sheetname "")
			)
			(fill
				(thermal_gap 0.5)
				(thermal_bridge_width 0.5)
				(island_removal_mode 0)
			)
			(polygon
				(pts
					(xy 243.654072 -368.427762) (xy 247.972072 -368.427762) (xy 248.454672 -368.427762) (xy 248.454672 -367.526062)
					(xy 243.171472 -367.526062) (xy 243.171472 -368.427762)
				)
			)
		)
	)
	(footprint ""
		(layer "F.Cu")
		(at 117.700044 -194.360038)
		(property "Reference" "H55"
			(at -4.12242 -5.192014 0)
			(unlocked yes)
			(layer "F.SilkS")
			(effects
				(font
					(size 0.7874 0.5842)
					(thickness 0.1524)
				)
				(justify left)
			)
		)
		(property "Value" ""
			(at 0 0 0)
			(layer "F.Fab")
			(effects
				(font
					(size 1.27 1.27)
				)
			)
		)
		(duplicate_pad_numbers_are_jumpers no)
		(pad "1" thru_hole circle
			(at 0 0)
			(size 10.0076 10.0076)
			(drill 5.6134)
			(layers "*.Cu" "*.Mask")
			(remove_unused_layers no)
			(net "GND")
			(clearance -1.9431)
		)
	)
)
